FILE_TYPE = CONNECTIVITY;
{Allegro Design Entry HDL 16.6-p007 (v16-6-112F) 10/10/2012}
"PAGE_NUMBER" = 165;
0"NC";
END.
